FILE_TYPE = CONNECTIVITY;
{Allegro Design Entry HDL 16.6-p007 (v16-6-112F) 10/10/2012}
"PAGE_NUMBER" = 142;
0"NC";
1"P3V3_STBY\g";
2"GND\g";
3"P3V3_STBY\g";
4"P3V3_STBY\g";
5"FM_ALL_WAKE_N";
6"FM_PE_SLOTX24_WAKE_N";
7"FM_PE_BMC_WAKE_N";
8"FM_PE_OCP_WAKE_N";
9"FM_PE_M2_WAKE_N";
10"FM_PE_SPRV_WAKE_N";
11"IRQ_LVC3_WAKE_N";
12"IRQ_LVC3_WAKE_R_N";
13"PU_TRI_STATE_EN";
%"TTL1G126_A"
"1","(-3500,2250)","6","mstr_ttl","I1";
;
CDS_SEC"1"
VALUE"74HC1G126"
MATERIAL"IC"
LOCATION"U8E4"
PART_NUMBER"A79322-001"
POWER_GROUP"VCC=P3V3_STBY;GND=GND;"
CDS_LIB"mstr_ttl"
SEC_TYPE"SOT"
BOM_COST"SB"
SEC"1"
ROOM"PCIE_WAKE_BUFFER"
CDS_LOCATION"U8E4"
PACK_TYPE"SOT";
"OE"
$PN"1"13;
"Y"
$PN"4"12;
"A"
$PN"2"5;
%"RES"
"1","(-4550,3100)","0","mstr_discrete","I18";
;
CDS_SEC"1"
PACK_TYPE"0402"
MATERIAL"EMPTY"
LOCATION"R8E29"
VALUE"0.0"
TOLERANCE"5%"
PART_NUMBER"G21497-005"
WATTAGE"1/16W"
SEC"1"
SEC_TYPE"0402"
ROOM"PCIE_WAKE_BUFFER"
BOM_COST"SB"
CDS_LOCATION"R8E29"
CDS_LIB"mstr_discrete";
"B"
$PN"2"5;
"A"
$PN"1"7;
%"RES"
"1","(-2600,2250)","0","mstr_discrete","I2";
;
CDS_SEC"1"
WATTAGE"1/16W"
PACK_TYPE"0402"
LOCATION"R8E17"
TOLERANCE"1%"
MATERIAL"CHIP"
VALUE"33.2"
PART_NUMBER"G21796-074"
ROOM"PCIE_WAKE_BUFFER"
CDS_LOCATION"R8E17"
SEC"1"
BOM_COST"SB"
SEC_TYPE"0402"
CDS_LIB"mstr_discrete";
"B"
$PN"2"11;
"A"
$PN"1"12;
%"CAP_A"
"1","(-3500,1550)","0","dev_discrete","I20";
;
VALUE"0.1UF"
VOLTAGE"16V"
LOCATION"C8E5"
PACK_TYPE"0402V"
PART_NUMBER"A36096-030"
MATERIAL"X7R"
TOLERANCE"10%"
BOM_COST"SB"
SEC_TYPE"0402V"
SEC"1"
ROOM"PCIE_WAKE_BUFFER"
CDS_LOCATION"C8E5"
CDS_SEC"1"
CDS_LIB"dev_discrete";
"B"
$PN"2"2;
"A"
$PN"1"1;
%"P3V3_STBY"
"1","(-3500,1775)","0","mstr_symbols","I21";
;
HDL_POWER"P3V3_STBY"
BODY_TYPE"PLUMBING"
SIZE"1B"
CDS_LIB"mstr_symbols"
VOLTAGE"3.3V";
"G\NAC"1;
%"GND"
"1","(-3500,1250)","0","mstr_symbols","I22";
;
HDL_POWER"GND"
BODY_TYPE"PLUMBING"
CDS_LIB"mstr_symbols"
SIZE"1B"
VOLTAGE"0.0V";
"A\NAC"2;
%"P3V3_STBY"
"1","(-3800,3900)","0","mstr_symbols","I24";
;
VOLTAGE"3.3V"
CDS_LIB"mstr_symbols"
SIZE"1B"
BODY_TYPE"PLUMBING"
HDL_POWER"P3V3_STBY";
"G\NAC"3;
%"RES"
"1","(-2850,2700)","0","mstr_discrete","I3";
;
CDS_SEC"1"
VALUE"4.75K"
WATTAGE"1/16W"
MATERIAL"CHIP"
PACK_TYPE"0402"
LOCATION"R8E23"
PART_NUMBER"G21796-072"
TOLERANCE"1%"
BOM_COST"SB"
SEC"1"
ROOM"PCIE_WAKE_BUFFER"
SEC_TYPE"0402"
CDS_LOCATION"R8E23"
CDS_LIB"mstr_discrete";
"B"
$PN"2"4;
"A"
$PN"1"13;
%"RES"
"1","(-4550,2250)","0","mstr_discrete","I30";
;
CDS_SEC"1"
LOCATION"R8E26"
VALUE"0.0"
TOLERANCE"5%"
WATTAGE"1/16W"
PACK_TYPE"0402"
PART_NUMBER"G21497-005"
MATERIAL"CHIP"
CDS_LIB"mstr_discrete"
ROOM"PCIE_WAKE_BUFFER"
CDS_LOCATION"R8E26"
SEC"1"
SEC_TYPE"0402";
"B"
$PN"2"5;
"A"
$PN"1"8;
%"RES"
"1","(-4550,2450)","0","mstr_discrete","I31";
;
CDS_SEC"1"
LOCATION"R8E28"
VALUE"0.0"
PACK_TYPE"0402"
PART_NUMBER"G21497-005"
MATERIAL"CHIP"
WATTAGE"1/16W"
TOLERANCE"5%"
CDS_LIB"mstr_discrete"
ROOM"PCIE_WAKE_BUFFER"
SEC"1"
SEC_TYPE"0402"
CDS_LOCATION"R8E28";
"B"
$PN"2"5;
"A"
$PN"1"6;
%"RES"
"1","(-4550,2650)","0","mstr_discrete","I32";
;
CDS_SEC"1"
TOLERANCE"5%"
MATERIAL"CHIP"
PACK_TYPE"0402"
PART_NUMBER"G21497-005"
LOCATION"R8E27"
VALUE"0.0"
WATTAGE"1/16W"
CDS_LIB"mstr_discrete"
ROOM"PCIE_WAKE_BUFFER"
CDS_LOCATION"R8E27"
SEC"1"
SEC_TYPE"0402";
"B"
$PN"2"5;
"A"
$PN"1"9;
%"RES"
"1","(-4550,2850)","0","mstr_discrete","I33";
;
CDS_SEC"1"
WATTAGE"1/16W"
TOLERANCE"5%"
LOCATION"R8E21"
VALUE"0.0"
PART_NUMBER"G21497-005"
PACK_TYPE"0402"
MATERIAL"CHIP"
CDS_LIB"mstr_discrete"
SEC"1"
SEC_TYPE"0402"
ROOM"PCIE_WAKE_BUFFER"
CDS_LOCATION"R8E21";
"B"
$PN"2"5;
"A"
$PN"1"10;
%"2K15R2F-1-GP"
"1","(-4800,3525)","0","w_hdl","I34";
;
CDS_SEC"1"
CDS_LOCATION"R8E36"
ATTRIBUTE"2.15K OHM"
TOLERANCE"1%"
PACK_SIZE"0402"
RATED"1/16W"
LOCATION"R8E36"
VALUE"2K15R2F-1-GP"
CDS_LMAN_SYM_OUTLINE"-50,75,50,-75"
CDS_LIB"w_hdl"
PART_NUMBER"64.21515.6DL"
PACK_TYPE"SMD-RG1"
SEC"1"
SEC_TYPE"SMD-RG1";
"2"
$PN"2"6;
"1"
$PN"1"3;
%"2K15R2F-1-GP"
"1","(-3800,3525)","0","w_hdl","I35";
;
CDS_SEC"1"
CDS_LOCATION"R8E30"
LOCATION"R8E30"
TOLERANCE"1%"
PACK_SIZE"0402"
VALUE"2K15R2F-1-GP"
ATTRIBUTE"2.15K OHM"
RATED"1/16W"
CDS_LMAN_SYM_OUTLINE"-50,75,50,-75"
CDS_LIB"w_hdl"
PART_NUMBER"64.21515.6DL"
SEC_TYPE"SMD-RG1"
SEC"1"
PACK_TYPE"SMD-RG1";
"2"
$PN"2"5;
"1"
$PN"1"3;
%"P3V3_STBY"
"1","(-2525,2950)","0","mstr_symbols","I4";
;
HDL_POWER"P3V3_STBY"
BODY_TYPE"PLUMBING"
SIZE"1B"
CDS_LIB"mstr_symbols"
VOLTAGE"3.3V";
"G\NAC"4;
END.
